(kicad_pcb
	(version 20260206)
	(generator "pcbnew")
	(generator_version "10.0")
	(general
		(thickness 1.6)
		(legacy_teardrops no)
	)
	(paper "A4")
	(title_block
		(title "03242023_DA0F0TMBIJ0_F0T_Motherboard_J_brd_V01_OCP.brd")
		(comment 1 "Grand Teton / footprints 2855-2855 of 6105")
	)
	(layers
		(0 "F.Cu" signal "TOP")
		(4 "In1.Cu" signal "GND")
		(6 "In2.Cu" signal "IN1")
		(8 "In3.Cu" signal "GND1")
		(10 "In4.Cu" signal "IN2")
		(12 "In5.Cu" signal "GND2")
		(14 "In6.Cu" signal "IN3")
		(16 "In7.Cu" signal "GND3")
		(18 "In8.Cu" signal "VCC")
		(20 "In9.Cu" signal "VCC1")
		(22 "In10.Cu" signal "GND4")
		(24 "In11.Cu" signal "IN4")
		(26 "In12.Cu" signal "GND5")
		(28 "In13.Cu" signal "IN5")
		(30 "In14.Cu" signal "GND6")
		(32 "In15.Cu" signal "IN6")
		(34 "In16.Cu" signal "GND7")
		(2 "B.Cu" signal "BOTTOM")
		(9 "F.Adhes" user "F.Adhesive")
		(11 "B.Adhes" user "B.Adhesive")
		(13 "F.Paste" user "Package Geometry/Pastemask Top")
		(15 "B.Paste" user "Package Geometry/Pastemask Bottom")
		(5 "F.SilkS" user "Ref Des/Silkscreen Top")
		(7 "B.SilkS" user "Ref Des/Silkscreen Bottom")
		(1 "F.Mask" user "Board Geometry/Soldermask Top")
		(3 "B.Mask" user "Board Geometry/Soldermask Bottom")
		(17 "Dwgs.User" user "User.Drawings")
		(19 "Cmts.User" user "User.Comments")
		(21 "Eco1.User" user "User.Eco1")
		(23 "Eco2.User" user "User.Eco2")
		(25 "Edge.Cuts" user "Board Geometry/Outline")
		(27 "Margin" user)
		(31 "F.CrtYd" user "Package Geometry/Place Bound Top")
		(29 "B.CrtYd" user "Package Geometry/Place Bound Bottom")
		(35 "F.Fab" user "Ref Des/Assembly Top")
		(33 "B.Fab" user "Ref Des/Assembly Bottom")
	)
	(footprint ""
		(layer "F.Cu")
		(at 194.346322 -79.057246)
		(property "Reference" "C640"
			(at 0 0 0)
			(layer "F.SilkS")
			(hide yes)
			(effects
				(font
					(size 1.27 1.27)
				)
			)
		)
		(property "Value" ""
			(at 0 0 0)
			(layer "F.Fab")
			(effects
				(font
					(size 1.27 1.27)
				)
			)
		)
		(duplicate_pad_numbers_are_jumpers no)
		(fp_line
			(start -0.7874 -0.4064)
			(end 0.7874 -0.4064)
			(stroke
				(width 0.1524)
				(type default)
			)
			(layer "F.SilkS")
		)
		(fp_line
			(start -0.7874 0.4064)
			(end -0.7874 -0.4064)
			(stroke
				(width 0.1524)
				(type default)
			)
			(layer "F.SilkS")
		)
		(fp_line
			(start 0.7874 -0.4064)
			(end 0.7874 0.4064)
			(stroke
				(width 0.1524)
				(type default)
			)
			(layer "F.SilkS")
		)
		(fp_line
			(start 0.7874 0.4064)
			(end -0.7874 0.4064)
			(stroke
				(width 0.1524)
				(type default)
			)
			(layer "F.SilkS")
		)
		(fp_line
			(start -0.67945 -0.305054)
			(end -0.12065 -0.305054)
			(stroke
				(width 0.1)
				(type default)
			)
			(layer "F.Fab")
		)
		(fp_line
			(start -0.67945 0.3048)
			(end -0.67945 -0.305054)
			(stroke
				(width 0.1)
				(type default)
			)
			(layer "F.Fab")
		)
		(fp_line
			(start -0.12065 -0.305054)
			(end -0.12065 -0.2794)
			(stroke
				(width 0.1)
				(type default)
			)
			(layer "F.Fab")
		)
		(fp_line
			(start -0.12065 -0.2794)
			(end 0.12065 -0.2794)
			(stroke
				(width 0.1)
				(type default)
			)
			(layer "F.Fab")
		)
		(fp_line
			(start -0.12065 0.2794)
			(end -0.12065 0.3048)
			(stroke
				(width 0.1)
				(type default)
			)
			(layer "F.Fab")
		)
		(fp_line
			(start -0.12065 0.3048)
			(end -0.67945 0.3048)
			(stroke
				(width 0.1)
				(type default)
			)
			(layer "F.Fab")
		)
		(fp_line
			(start 0.120396 0.2794)
			(end -0.12065 0.2794)
			(stroke
				(width 0.1)
				(type default)
			)
			(layer "F.Fab")
		)
		(fp_line
			(start 0.120396 0.3048)
			(end 0.120396 0.2794)
			(stroke
				(width 0.1)
				(type default)
			)
			(layer "F.Fab")
		)
		(fp_line
			(start 0.12065 -0.3048)
			(end 0.67945 -0.3048)
			(stroke
				(width 0.1)
				(type default)
			)
			(layer "F.Fab")
		)
		(fp_line
			(start 0.12065 -0.2794)
			(end 0.12065 -0.3048)
			(stroke
				(width 0.1)
				(type default)
			)
			(layer "F.Fab")
		)
		(fp_line
			(start 0.67945 -0.3048)
			(end 0.67945 0.3048)
			(stroke
				(width 0.1)
				(type default)
			)
			(layer "F.Fab")
		)
		(fp_line
			(start 0.67945 0.3048)
			(end 0.120396 0.3048)
			(stroke
				(width 0.1)
				(type default)
			)
			(layer "F.Fab")
		)
		(pad "1" smd circle
			(at -0.40005 0)
			(size 0 0)
			(layers "F.Cu" "F.Mask" "F.Paste")
			(net "P3V3_AUX")
		)
		(pad "2" smd circle
			(at 0.40005 0)
			(size 0 0)
			(layers "F.Cu" "F.Mask" "F.Paste")
			(net "GND")
		)
	)
)
